(kicad_pcb
	(version 20241229)
	(generator "pcbnew")
	(generator_version "9.0")
	(general
		(thickness 1.61)
		(legacy_teardrops no)
	)
	(paper "A3")
	(title_block
		(title "RDIMM DDR5 Tester")
		(date "2026-05-21")
		(rev "2.2.0")
		(company "Antmicro")
		(comment 9 "footprints 352-356 of 796")
	)
	(layers
		(0 "F.Cu" signal)
		(4 "In1.Cu" power)
		(6 "In2.Cu" mixed)
		(8 "In3.Cu" power)
		(10 "In4.Cu" mixed)
		(12 "In5.Cu" power)
		(14 "In6.Cu" mixed)
		(16 "In7.Cu" power)
		(18 "In8.Cu" power)
		(20 "In9.Cu" mixed)
		(22 "In10.Cu" power)
		(2 "B.Cu" signal)
		(9 "F.Adhes" user "F.Adhesive")
		(11 "B.Adhes" user "B.Adhesive")
		(13 "F.Paste" user)
		(15 "B.Paste" user)
		(5 "F.SilkS" user "F.Silkscreen")
		(7 "B.SilkS" user "B.Silkscreen")
		(1 "F.Mask" user)
		(3 "B.Mask" user)
		(17 "Dwgs.User" user "User.Drawings")
		(19 "Cmts.User" user "User.Comments")
		(21 "Eco1.User" user "User.Eco1")
		(23 "Eco2.User" user "User.Eco2")
		(25 "Edge.Cuts" user)
		(27 "Margin" user)
		(31 "F.CrtYd" user "F.Courtyard")
		(29 "B.CrtYd" user "B.Courtyard")
		(35 "F.Fab" user)
		(33 "B.Fab" user)
	)
	(footprint "antmicro-footprints:LED_0603_1608Metric_G"
		(layer "F.Cu")
		(at 135.823499 185.549 90)
		(descr "LED SMD 0603 Green")
		(tags "LED SMD 0603 Green")
		(property "Reference" "D10"
			(at -0.001 -0.901 90)
			(layer "F.SilkS")
			(hide yes)
			(effects
				(font
					(size 0.7 0.7)
					(thickness 0.15)
				)
				(justify left bottom)
			)
		)
		(property "Value" "LED_G_0603_KP-1608CGCK"
			(at -0.001 1.599 90)
			(layer "F.Fab")
			(effects
				(font
					(size 0.7 0.7)
					(thickness 0.15)
				)
				(justify left bottom)
			)
		)
		(property "Datasheet" "http://www.kingbright.com/attachments/file/psearch//000/00/00/KP-1608CGCK(Ver.23B).pdf"
			(at 0 0 90)
			(layer "F.Fab")
			(hide yes)
			(effects
				(font
					(size 1.27 1.27)
					(thickness 0.15)
				)
			)
		)
		(property "MPN" "KP-1608CGCK"
			(at 0 0 90)
			(unlocked yes)
			(layer "F.Fab")
			(hide yes)
			(effects
				(font
					(size 1 1)
					(thickness 0.15)
				)
			)
		)
		(property "Manufacturer" "Kingbright"
			(at 0 0 90)
			(unlocked yes)
			(layer "F.Fab")
			(hide yes)
			(effects
				(font
					(size 1 1)
					(thickness 0.15)
				)
			)
		)
		(property "Color" "Green"
			(at 0 0 90)
			(unlocked yes)
			(layer "F.Fab")
			(hide yes)
			(effects
				(font
					(size 1 1)
					(thickness 0.15)
				)
			)
		)
		(property "Author" "Antmicro"
			(at 0 0 90)
			(unlocked yes)
			(layer "F.Fab")
			(hide yes)
			(effects
				(font
					(size 1 1)
					(thickness 0.15)
				)
			)
		)
		(property "License" "Apache-2.0"
			(at 0 0 90)
			(unlocked yes)
			(layer "F.Fab")
			(hide yes)
			(effects
				(font
					(size 1 1)
					(thickness 0.15)
				)
			)
		)
		(sheetname "/Debug FTDI + VNA/")
		(sheetfile "debug-ftdi.kicad_sch")
		(attr smd)
		(fp_line
			(start 0.22 -0.35)
			(end -0.22 -0.35)
			(stroke
				(width 0.15)
				(type solid)
			)
			(layer "F.SilkS")
		)
		(fp_line
			(start -1.18 -0.319)
			(end -1.18 0.321)
			(stroke
				(width 0.15)
				(type solid)
			)
			(layer "F.SilkS")
		)
		(fp_line
			(start 0.105328 0.001008)
			(end 0.24 0.001)
			(stroke
				(width 0.1)
				(type solid)
			)
			(layer "F.SilkS")
		)
		(fp_line
			(start -0.094672 0.001008)
			(end 0.105328 -0.198992)
			(stroke
				(width 0.1)
				(type solid)
			)
			(layer "F.SilkS")
		)
		(fp_line
			(start -0.094672 0.001008)
			(end -0.24 0.001008)
			(stroke
				(width 0.1)
				(type solid)
			)
			(layer "F.SilkS")
		)
		(fp_line
			(start 0.105328 0.201008)
			(end 0.105328 -0.198992)
			(stroke
				(width 0.1)
				(type solid)
			)
			(layer "F.SilkS")
		)
		(fp_line
			(start 0.105328 0.201008)
			(end -0.094672 0.001008)
			(stroke
				(width 0.1)
				(type solid)
			)
			(layer "F.SilkS")
		)
		(fp_line
			(start -0.094672 0.201008)
			(end -0.094672 -0.198992)
			(stroke
				(width 0.1)
				(type solid)
			)
			(layer "F.SilkS")
		)
		(fp_line
			(start 0.22 0.35)
			(end -0.22 0.35)
			(stroke
				(width 0.15)
				(type solid)
			)
			(layer "F.SilkS")
		)
		(fp_rect
			(start 1.25 0.65)
			(end -1.25 -0.65)
			(stroke
				(width 0.05)
				(type solid)
			)
			(fill no)
			(layer "F.CrtYd")
		)
		(fp_line
			(start 0.201 -0.202)
			(end -0.101 0)
			(stroke
				(width 0.15)
				(type solid)
			)
			(layer "F.Fab")
		)
		(fp_line
			(start -0.199 -0.202)
			(end -0.199 0.1)
			(stroke
				(width 0.15)
				(type solid)
			)
			(layer "F.Fab")
		)
		(fp_line
			(start 0.599 0)
			(end 0.201 0)
			(stroke
				(width 0.15)
				(type solid)
			)
			(layer "F.Fab")
		)
		(fp_line
			(start 0.201 0)
			(end 0.201 -0.202)
			(stroke
				(width 0.15)
				(type solid)
			)
			(layer "F.Fab")
		)
		(fp_line
			(start -0.101 0)
			(end 0.201 0.2)
			(stroke
				(width 0.15)
				(type solid)
			)
			(layer "F.Fab")
		)
		(fp_line
			(start -0.199 0)
			(end -0.597 0)
			(stroke
				(width 0.15)
				(type solid)
			)
			(layer "F.Fab")
		)
		(fp_line
			(start 0.201 0.2)
			(end 0.201 0)
			(stroke
				(width 0.15)
				(type solid)
			)
			(layer "F.Fab")
		)
		(fp_line
			(start -0.199 0.2)
			(end -0.199 0.1)
			(stroke
				(width 0.15)
				(type solid)
			)
			(layer "F.Fab")
		)
		(fp_rect
			(start 0.848 0.4)
			(end -0.85 -0.402)
			(stroke
				(width 0.15)
				(type solid)
			)
			(fill no)
			(layer "F.Fab")
		)
		(fp_text user "${REFERENCE}"
			(at -1.4224 5.999 90)
			(layer "F.Fab")
			(effects
				(font
					(size 0.7 0.7)
					(thickness 0.15)
				)
				(justify left bottom)
			)
		)
		(fp_text user "Author: Antmicro"
			(at -1.4224 4.799 90)
			(layer "F.Fab")
			(effects
				(font
					(size 0.7 0.7)
					(thickness 0.15)
				)
				(justify left bottom)
			)
		)
		(fp_text user "License: Apache-2.0"
			(at -1.4224 3.599 90)
			(layer "F.Fab")
			(effects
				(font
					(size 0.7 0.7)
					(thickness 0.15)
				)
				(justify left bottom)
			)
		)
		(pad "1" smd roundrect
			(at -0.7 0 270)
			(size 0.8 1)
			(layers "F.Cu" "F.Mask" "F.Paste")
			(roundrect_rratio 0.2)
			(net 1 "GND")
			(pinfunction "C")
			(pintype "passive")
		)
		(pad "2" smd roundrect
			(at 0.7 0 270)
			(size 0.8 1)
			(layers "F.Cu" "F.Mask" "F.Paste")
			(roundrect_rratio 0.2)
			(net 39 "Net-(D10-A)")
			(pinfunction "A")
			(pintype "passive")
		)
	)
	(footprint "antmicro-footprints:R_0402_1005Metric"
		(layer "F.Cu")
		(at 127.681 166.1125 90)
		(descr "Resistor SMD 0402")
		(tags "resistor SMD 0402")
		(property "Reference" "R225"
			(at 0.9125 3.969 90)
			(layer "F.SilkS")
			(effects
				(font
					(size 0.7 0.7)
					(thickness 0.15)
				)
				(justify left bottom)
			)
		)
		(property "Value" "R_64k9_0402"
			(at -1.011843 1.772047 90)
			(layer "F.Fab")
			(effects
				(font
					(size 0.7 0.7)
					(thickness 0.15)
				)
				(justify left bottom)
			)
		)
		(property "Datasheet" "https://www.bourns.com/docs/product-datasheets/cr.pdf"
			(at 0 0 90)
			(layer "F.Fab")
			(hide yes)
			(effects
				(font
					(size 1.27 1.27)
					(thickness 0.15)
				)
			)
		)
		(property "MPN" "CR0402-FX-6492GLF"
			(at 0 0 90)
			(unlocked yes)
			(layer "F.Fab")
			(hide yes)
			(effects
				(font
					(size 1 1)
					(thickness 0.15)
				)
			)
		)
		(property "Manufacturer" "Bourns"
			(at 0 0 90)
			(unlocked yes)
			(layer "F.Fab")
			(hide yes)
			(effects
				(font
					(size 1 1)
					(thickness 0.15)
				)
			)
		)
		(property "License" "Apache-2.0"
			(at 0 0 90)
			(unlocked yes)
			(layer "F.Fab")
			(hide yes)
			(effects
				(font
					(size 1 1)
					(thickness 0.15)
				)
			)
		)
		(property "Author" "Antmicro"
			(at 0 0 90)
			(unlocked yes)
			(layer "F.Fab")
			(hide yes)
			(effects
				(font
					(size 1 1)
					(thickness 0.15)
				)
			)
		)
		(property "Val" "64k9"
			(at 0 0 90)
			(unlocked yes)
			(layer "F.Fab")
			(hide yes)
			(effects
				(font
					(size 1 1)
					(thickness 0.15)
				)
			)
		)
		(property "Tolerance" "1%"
			(at 0 0 90)
			(unlocked yes)
			(layer "F.Fab")
			(hide yes)
			(effects
				(font
					(size 1 1)
					(thickness 0.15)
				)
			)
		)
		(sheetname "/HDMI + SD Card/")
		(sheetfile "hdmi-sd-card.kicad_sch")
		(attr smd exclude_from_bom dnp)
		(fp_rect
			(start -0.925 -0.47)
			(end 0.925 0.47)
			(stroke
				(width 0.05)
				(type default)
			)
			(fill no)
			(layer "F.CrtYd")
		)
		(fp_rect
			(start -0.5 -0.25)
			(end 0.5 0.25)
			(stroke
				(width 0.15)
				(type solid)
			)
			(fill no)
			(layer "F.Fab")
		)
		(fp_text user "${REFERENCE}"
			(at -0.95 3.168 90)
			(layer "F.Fab")
			(effects
				(font
					(size 0.7 0.7)
					(thickness 0.15)
				)
				(justify left bottom)
			)
		)
		(fp_text user "License: Apache-2.0"
			(at -0.95 5.169 90)
			(layer "F.Fab")
			(effects
				(font
					(size 0.7 0.7)
					(thickness 0.15)
				)
				(justify left bottom)
			)
		)
		(fp_text user "Author: Antmicro"
			(at -0.95 4.169 90)
			(layer "F.Fab")
			(effects
				(font
					(size 0.7 0.7)
					(thickness 0.15)
				)
				(justify left bottom)
			)
		)
		(pad "1" smd roundrect
			(at -0.48 0 90)
			(size 0.59 0.64)
			(layers "F.Cu" "F.Mask" "F.Paste")
			(roundrect_rratio 0.25)
			(net 710 "/HDMI + SD Card/I2C_EN{slash}PIN")
			(pintype "passive")
		)
		(pad "2" smd roundrect
			(at 0.48 0 90)
			(size 0.59 0.64)
			(layers "F.Cu" "F.Mask" "F.Paste")
			(roundrect_rratio 0.25)
			(net 151 "+3V3")
			(pintype "passive")
		)
	)
	(footprint "antmicro-footprints:SOD-523"
		(layer "F.Cu")
		(at 116.981 174.668 90)
		(property "Reference" "D14"
			(at -0.2495 1.615 90)
			(layer "F.SilkS")
			(effects
				(font
					(size 0.7 0.7)
					(thickness 0.15)
				)
				(justify left bottom)
			)
		)
		(property "Value" "BAT54-02V-G3-08"
			(at 0 1.499 90)
			(layer "F.Fab")
			(effects
				(font
					(size 0.7 0.7)
					(thickness 0.15)
				)
				(justify left bottom)
			)
		)
		(property "Datasheet" "https://www.vishay.com/docs/85633/bat5402v.pdf"
			(at 0 0 90)
			(layer "F.Fab")
			(hide yes)
			(effects
				(font
					(size 1.27 1.27)
					(thickness 0.15)
				)
			)
		)
		(property "MPN" "BAT54-02V-G3-08"
			(at 0 0 90)
			(unlocked yes)
			(layer "F.Fab")
			(hide yes)
			(effects
				(font
					(size 1 1)
					(thickness 0.15)
				)
			)
		)
		(property "Manufacturer" "Vishay"
			(at 0 0 90)
			(unlocked yes)
			(layer "F.Fab")
			(hide yes)
			(effects
				(font
					(size 1 1)
					(thickness 0.15)
				)
			)
		)
		(property "Author" "Antmicro"
			(at 0 0 90)
			(unlocked yes)
			(layer "F.Fab")
			(hide yes)
			(effects
				(font
					(size 1 1)
					(thickness 0.15)
				)
			)
		)
		(property "License" "Apache-2.0"
			(at 0 0 90)
			(unlocked yes)
			(layer "F.Fab")
			(hide yes)
			(effects
				(font
					(size 1 1)
					(thickness 0.15)
				)
			)
		)
		(sheetname "/HDMI + SD Card/")
		(sheetfile "hdmi-sd-card.kicad_sch")
		(attr smd)
		(fp_line
			(start -0.35 -0.5)
			(end -0.35 0.5)
			(stroke
				(width 0.15)
				(type solid)
			)
			(layer "F.SilkS")
		)
		(fp_rect
			(start -1 -0.6)
			(end 1 0.6)
			(stroke
				(width 0.05)
				(type solid)
			)
			(fill no)
			(layer "F.CrtYd")
		)
		(fp_line
			(start 0.65 -0.425)
			(end 0.65 0.423)
			(stroke
				(width 0.15)
				(type solid)
			)
			(layer "F.Fab")
		)
		(fp_line
			(start -0.652 -0.425)
			(end 0.65 -0.425)
			(stroke
				(width 0.15)
				(type solid)
			)
			(layer "F.Fab")
		)
		(fp_line
			(start -0.35 -0.4)
			(end -0.35 0.4)
			(stroke
				(width 0.15)
				(type solid)
			)
			(layer "F.Fab")
		)
		(fp_line
			(start -0.652 0.423)
			(end -0.652 -0.425)
			(stroke
				(width 0.15)
				(type solid)
			)
			(layer "F.Fab")
		)
		(fp_line
			(start -0.652 0.423)
			(end 0.65 0.423)
			(stroke
				(width 0.15)
				(type solid)
			)
			(layer "F.Fab")
		)
		(fp_text user "License: Apache-2.0"
			(at -1.276 5.9 90)
			(layer "F.Fab")
			(effects
				(font
					(size 0.7 0.7)
					(thickness 0.15)
				)
				(justify left bottom)
			)
		)
		(fp_text user "Author: Antmicro"
			(at -1.276 4.7 90)
			(layer "F.Fab")
			(effects
				(font
					(size 0.7 0.7)
					(thickness 0.15)
				)
				(justify left bottom)
			)
		)
		(fp_text user "${REFERENCE}"
			(at -1.276 3.499 90)
			(layer "F.Fab")
			(effects
				(font
					(size 0.7 0.7)
					(thickness 0.15)
				)
				(justify left bottom)
			)
		)
		(pad "1" smd roundrect
			(at -0.701 0 90)
			(size 0.5 0.6)
			(layers "F.Cu" "F.Mask" "F.Paste")
			(roundrect_rratio 0.25)
			(net 8 "/HDMI + SD Card/HDMI_CONN_5V")
			(pinfunction "C")
			(pintype "passive")
		)
		(pad "2" smd roundrect
			(at 0.699 0 90)
			(size 0.5 0.6)
			(layers "F.Cu" "F.Mask" "F.Paste")
			(roundrect_rratio 0.25)
			(net 33 "/HDMI + SD Card/HDMI_5V")
			(pinfunction "A")
			(pintype "passive")
		)
	)
	(footprint "antmicro-footprints:TP_SMD_1mm"
		(layer "F.Cu")
		(at 243.23 134.757 90)
		(property "Reference" "TP7"
			(at 0 -0.731898 90)
			(layer "F.SilkS")
			(hide yes)
			(effects
				(font
					(size 0.7 0.7)
					(thickness 0.15)
				)
				(justify left bottom)
			)
		)
		(property "Value" "TP_1mm_SMD"
			(at 0 1.4 90)
			(layer "F.Fab")
			(effects
				(font
					(size 0.7 0.7)
					(thickness 0.15)
				)
				(justify left bottom)
			)
		)
		(property "MPN" ""
			(at 0 0 90)
			(unlocked yes)
			(layer "F.Fab")
			(hide yes)
			(effects
				(font
					(size 1 1)
					(thickness 0.15)
				)
			)
		)
		(property "Manufacturer" ""
			(at 0 0 90)
			(unlocked yes)
			(layer "F.Fab")
			(hide yes)
			(effects
				(font
					(size 1 1)
					(thickness 0.15)
				)
			)
		)
		(property "Author" "Antmicro"
			(at 0 0 90)
			(unlocked yes)
			(layer "F.Fab")
			(hide yes)
			(effects
				(font
					(size 1 1)
					(thickness 0.15)
				)
			)
		)
		(property "License" "Apache-2.0"
			(at 0 0 90)
			(unlocked yes)
			(layer "F.Fab")
			(hide yes)
			(effects
				(font
					(size 1 1)
					(thickness 0.15)
				)
			)
		)
		(sheetname "/I^{2}C + I3C/")
		(sheetfile "i2c.kicad_sch")
		(attr exclude_from_pos_files)
		(fp_circle
			(center 0 0)
			(end 0.6 0)
			(stroke
				(width 0.05)
				(type default)
			)
			(fill no)
			(layer "F.CrtYd")
		)
		(fp_text user "${REFERENCE}"
			(at -0.5 2.8 90)
			(layer "F.Fab")
			(effects
				(font
					(size 0.7 0.7)
					(thickness 0.15)
				)
				(justify left bottom)
			)
		)
		(fp_text user "Author: Antmicro"
			(at -0.5 4 90)
			(layer "F.Fab")
			(effects
				(font
					(size 0.7 0.7)
					(thickness 0.15)
				)
				(justify left bottom)
			)
		)
		(fp_text user "License: Apache-2.0"
			(at -0.5 5.2 90)
			(layer "F.Fab")
			(effects
				(font
					(size 0.7 0.7)
					(thickness 0.15)
				)
				(justify left bottom)
			)
		)
		(pad "1" smd circle
			(at 0 0 90)
			(size 1 1)
			(layers "F.Cu" "F.Mask")
			(net 796 "Net-(U45-EN)")
			(pinfunction "1")
			(pintype "passive")
		)
	)
	(footprint "antmicro-footprints:R_0402_1005Metric"
		(layer "F.Cu")
		(at 254.1055 160.171 180)
		(descr "Resistor SMD 0402")
		(tags "resistor SMD 0402")
		(property "Reference" "R155"
			(at -0.5945 -1.429 0)
			(layer "F.SilkS")
			(effects
				(font
					(size 0.7 0.7)
					(thickness 0.15)
				)
				(justify right bottom)
			)
		)
		(property "Value" "R_0R_0402"
			(at -1.011843 1.772047 0)
			(layer "F.Fab")
			(effects
				(font
					(size 0.7 0.7)
					(thickness 0.15)
				)
				(justify right bottom)
			)
		)
		(property "Datasheet" "https://industrial.panasonic.com/cdbs/www-data/pdf/RDA0000/AOA0000C301.pdf"
			(at 0 0 180)
			(layer "F.Fab")
			(hide yes)
			(effects
				(font
					(size 1.27 1.27)
					(thickness 0.15)
				)
			)
		)
		(property "Manufacturer" "Panasonic"
			(at 0 0 180)
			(unlocked yes)
			(layer "F.Fab")
			(hide yes)
			(effects
				(font
					(size 1 1)
					(thickness 0.15)
				)
			)
		)
		(property "MPN" "ERJ2GE0R00X"
			(at 0 0 180)
			(unlocked yes)
			(layer "F.Fab")
			(hide yes)
			(effects
				(font
					(size 1 1)
					(thickness 0.15)
				)
			)
		)
		(property "Val" "0R"
			(at 0 0 180)
			(unlocked yes)
			(layer "F.Fab")
			(hide yes)
			(effects
				(font
					(size 1 1)
					(thickness 0.15)
				)
			)
		)
		(property "License" "Apache-2.0"
			(at 0 0 180)
			(unlocked yes)
			(layer "F.Fab")
			(hide yes)
			(effects
				(font
					(size 1 1)
					(thickness 0.15)
				)
			)
		)
		(property "Author" "Antmicro"
			(at 0 0 180)
			(unlocked yes)
			(layer "F.Fab")
			(hide yes)
			(effects
				(font
					(size 1 1)
					(thickness 0.15)
				)
			)
		)
		(property "Tolerance" "~"
			(at 0 0 180)
			(unlocked yes)
			(layer "F.Fab")
			(hide yes)
			(effects
				(font
					(size 1 1)
					(thickness 0.15)
				)
			)
		)
		(property "Current" "1A"
			(at 0 0 180)
			(unlocked yes)
			(layer "F.Fab")
			(hide yes)
			(effects
				(font
					(size 1 1)
					(thickness 0.15)
				)
			)
		)
		(sheetname "/Supply/DC-DC IO/")
		(sheetfile "dc-dc-io.kicad_sch")
		(attr smd)
		(fp_rect
			(start -0.925 -0.47)
			(end 0.925 0.47)
			(stroke
				(width 0.05)
				(type default)
			)
			(fill no)
			(layer "F.CrtYd")
		)
		(fp_rect
			(start -0.5 -0.25)
			(end 0.5 0.25)
			(stroke
				(width 0.15)
				(type solid)
			)
			(fill no)
			(layer "F.Fab")
		)
		(fp_text user "Author: Antmicro"
			(at -0.95 4.169 180)
			(layer "F.Fab")
			(effects
				(font
					(size 0.7 0.7)
					(thickness 0.15)
				)
				(justify left bottom)
			)
		)
		(fp_text user "${REFERENCE}"
			(at -0.95 3.168 180)
			(layer "F.Fab")
			(effects
				(font
					(size 0.7 0.7)
					(thickness 0.15)
				)
				(justify left bottom)
			)
		)
		(fp_text user "License: Apache-2.0"
			(at -0.95 5.169 180)
			(layer "F.Fab")
			(effects
				(font
					(size 0.7 0.7)
					(thickness 0.15)
				)
				(justify left bottom)
			)
		)
		(pad "1" smd roundrect
			(at -0.48 0 180)
			(size 0.59 0.64)
			(layers "F.Cu" "F.Mask" "F.Paste")
			(roundrect_rratio 0.25)
			(net 714 "/Supply/DC-DC IO/FB5")
			(pintype "passive")
		)
		(pad "2" smd roundrect
			(at 0.48 0 180)
			(size 0.59 0.64)
			(layers "F.Cu" "F.Mask" "F.Paste")
			(roundrect_rratio 0.25)
			(net 45 "/Supply/DC-DC IO/3V3_local")
			(pintype "passive")
		)
	)
)
